(kicad_pcb
	(version 20260206)
	(generator "pcbnew")
	(generator_version "10.0")
	(general
		(thickness 1.6)
		(legacy_teardrops no)
	)
	(paper "A4")
	(title_block
		(title "Bryce Canyon_F.DPB_16315-1-OCP.brd")
		(comment 1 "Bryce Canyon / footprints 1662-1668 of 2223")
	)
	(layers
		(0 "F.Cu" signal "TOP")
		(4 "In1.Cu" signal "L2GND")
		(6 "In2.Cu" signal "L3")
		(8 "In3.Cu" signal "L4GND")
		(10 "In4.Cu" signal "L5")
		(12 "In5.Cu" signal "L6VCC")
		(14 "In6.Cu" signal "L7VCC")
		(16 "In7.Cu" signal "L8")
		(18 "In8.Cu" signal "L9GND")
		(20 "In9.Cu" signal "L10")
		(22 "In10.Cu" signal "L11GND")
		(2 "B.Cu" signal "BOTTOM")
		(9 "F.Adhes" user "F.Adhesive")
		(11 "B.Adhes" user "B.Adhesive")
		(13 "F.Paste" user "Package Geometry/Pastemask Top")
		(15 "B.Paste" user "Package Geometry/Pastemask Bottom")
		(5 "F.SilkS" user "Ref Des/Silkscreen Top")
		(7 "B.SilkS" user "Ref Des/Silkscreen Bottom")
		(1 "F.Mask" user "Board Geometry/Soldermask Top")
		(3 "B.Mask" user "Board Geometry/Soldermask Bottom")
		(17 "Dwgs.User" user "User.Drawings")
		(19 "Cmts.User" user "User.Comments")
		(21 "Eco1.User" user "User.Eco1")
		(23 "Eco2.User" user "User.Eco2")
		(25 "Edge.Cuts" user "Board Geometry/Outline")
		(27 "Margin" user)
		(31 "F.CrtYd" user "Package Geometry/Place Bound Top")
		(29 "B.CrtYd" user "Package Geometry/Place Bound Bottom")
		(35 "F.Fab" user "Ref Des/Assembly Top")
		(33 "B.Fab" user "Ref Des/Assembly Bottom")
	)
	(footprint ""
		(layer "F.Cu")
		(at 356.289102 -162.749992 -90)
		(property "Reference" "VIA27"
			(at 0 0 270)
			(layer "F.SilkS")
			(hide yes)
			(effects
				(font
					(size 1.27 1.27)
				)
			)
		)
		(property "Value" "100OHM-8L-1D6MM-L18L16-GP"
			(at -3.7211 -4.5085 270)
			(unlocked yes)
			(layer "F.Fab")
			(hide yes)
			(effects
				(font
					(size 1.016 1.016)
					(thickness 0.1524)
				)
			)
		)
		(property "Device Type" "VIA-PCIE-4P-394076"
			(at -3.7211 -6.0325 270)
			(unlocked yes)
			(layer "F.Fab")
			(hide yes)
			(effects
				(font
					(size 1.016 1.016)
					(thickness 0.1524)
				)
			)
		)
		(duplicate_pad_numbers_are_jumpers no)
		(fp_rect
			(start -1.9685 0.381)
			(end 1.9685 -0.381)
			(stroke
				(width 0)
				(type default)
			)
			(fill no)
			(layer "F.CrtYd")
		)
		(fp_rect
			(start -1.9685 0.381)
			(end 1.9685 -0.381)
			(stroke
				(width 0)
				(type default)
			)
			(fill no)
			(layer "F.Fab")
		)
		(pad "1" thru_hole circle
			(at -1.5875 0 270)
			(size 0.508 0.508)
			(drill 0.254)
			(layers "*.Cu" "*.Mask")
			(remove_unused_layers no)
			(net "GND")
			(clearance 0.127)
			(thermal_gap 0.127)
		)
		(pad "2" thru_hole circle
			(at -0.5715 0 270)
			(size 0.508 0.508)
			(drill 0.254)
			(layers "*.Cu" "*.Mask")
			(remove_unused_layers no)
			(net "PHY_DRV_A_TO_SCC_A_19_DP")
			(clearance 0.127)
			(thermal_gap 0.127)
		)
		(pad "3" thru_hole circle
			(at 0.5715 0 270)
			(size 0.508 0.508)
			(drill 0.254)
			(layers "*.Cu" "*.Mask")
			(remove_unused_layers no)
			(net "PHY_DRV_A_TO_SCC_A_19_DN")
			(clearance 0.127)
			(thermal_gap 0.127)
		)
		(pad "4" thru_hole circle
			(at 1.5875 0 270)
			(size 0.508 0.508)
			(drill 0.254)
			(layers "*.Cu" "*.Mask")
			(remove_unused_layers no)
			(net "GND")
			(clearance 0.127)
			(thermal_gap 0.127)
		)
	)
	(footprint ""
		(layer "F.Cu")
		(at 80.900016 -324.39991)
		(property "Reference" "RLED27"
			(at 0 0 0)
			(layer "F.SilkS")
			(hide yes)
			(effects
				(font
					(size 1.27 1.27)
				)
			)
		)
		(property "Value" "LED-BY-19-GP"
			(at -2.132076 1.414018 0)
			(unlocked yes)
			(layer "F.Fab")
			(hide yes)
			(effects
				(font
					(size 1.016 1.016)
					(thickness 0.1524)
				)
			)
		)
		(property "Device Type" "LED-1615-4PH26"
			(at -2.132076 -0.109982 0)
			(unlocked yes)
			(layer "F.Fab")
			(hide yes)
			(effects
				(font
					(size 1.016 1.016)
					(thickness 0.1524)
				)
			)
		)
		(duplicate_pad_numbers_are_jumpers no)
		(fp_line
			(start -1.2954 0.254)
			(end -1.2954 1.6002)
			(stroke
				(width 0.508)
				(type default)
			)
			(layer "F.SilkS")
		)
		(fp_line
			(start -1.2954 1.6002)
			(end 1.2954 1.6002)
			(stroke
				(width 0.508)
				(type default)
			)
			(layer "F.SilkS")
		)
		(fp_line
			(start -1.1176 -1.4224)
			(end 1.1176 -1.4224)
			(stroke
				(width 0.1524)
				(type default)
			)
			(layer "F.SilkS")
		)
		(fp_line
			(start -1.1176 1.4224)
			(end -1.1176 -1.4224)
			(stroke
				(width 0.1524)
				(type default)
			)
			(layer "F.SilkS")
		)
		(fp_line
			(start 1.1176 -1.4224)
			(end 1.1176 1.4224)
			(stroke
				(width 0.1524)
				(type default)
			)
			(layer "F.SilkS")
		)
		(fp_line
			(start 1.1176 1.4224)
			(end -1.1176 1.4224)
			(stroke
				(width 0.1524)
				(type default)
			)
			(layer "F.SilkS")
		)
		(fp_line
			(start 1.2954 1.6002)
			(end 1.2954 0.254)
			(stroke
				(width 0.508)
				(type default)
			)
			(layer "F.SilkS")
		)
		(fp_rect
			(start -0.7493 0.8001)
			(end 0.7493 -0.8001)
			(stroke
				(width 0)
				(type default)
			)
			(fill no)
			(layer "F.CrtYd")
		)
		(fp_poly
			(pts
				(xy -1.3716 1.6764) (xy -1.3716 -1.6764) (xy 1.3716 -1.6764) (xy 1.3716 0.0635) (xy 0.7493 0.0635)
				(xy 0.7493 -0.8001) (xy -0.7493 -0.8001) (xy -0.7493 0.8001) (xy 0.7493 0.8001) (xy 0.7493 0.0762)
				(xy 1.3716 0.0762) (xy 1.3716 1.6764)
			)
			(stroke
				(width 0)
				(type default)
			)
			(fill no)
			(layer "F.CrtYd")
		)
		(fp_rect
			(start -1.3716 1.6764)
			(end 1.3716 -1.6764)
			(stroke
				(width 0)
				(type default)
			)
			(fill no)
			(layer "F.Fab")
		)
		(pad "1" smd rect
			(at 0.50038 -0.73025)
			(size 0.7112 0.8636)
			(layers "F.Cu" "F.Mask" "F.Paste")
			(net "DRV_ACT_26")
		)
		(pad "2" smd rect
			(at -0.50038 -0.73025)
			(size 0.7112 0.8636)
			(layers "F.Cu" "F.Mask" "F.Paste")
			(net "FLT_HDD26")
		)
		(pad "3" smd rect
			(at 0.50038 0.73025)
			(size 0.7112 0.8636)
			(layers "F.Cu" "F.Mask" "F.Paste")
			(net "DRV_ACT_26_N")
		)
		(pad "4" smd rect
			(at -0.50038 0.73025)
			(size 0.7112 0.8636)
			(layers "F.Cu" "F.Mask" "F.Paste")
			(net "FLT_HDD26_N")
		)
	)
	(footprint ""
		(layer "F.Cu")
		(at 143.072866 -130.894074)
		(property "Reference" "C546"
			(at 0 0 0)
			(layer "F.SilkS")
			(hide yes)
			(effects
				(font
					(size 1.27 1.27)
				)
			)
		)
		(property "Value" "SC2D2U25V5KX-2-GP"
			(at -0.0762 -6.1214 0)
			(unlocked yes)
			(layer "F.Fab")
			(hide yes)
			(effects
				(font
					(size 1.016 1.016)
					(thickness 0.1524)
				)
			)
		)
		(property "Device Type" "C805H54"
			(at -0.0762 -8.1534 0)
			(unlocked yes)
			(layer "F.Fab")
			(hide yes)
			(effects
				(font
					(size 1.016 1.016)
					(thickness 0.1524)
				)
			)
		)
		(duplicate_pad_numbers_are_jumpers no)
		(fp_line
			(start 0.635 0)
			(end -0.635 0)
			(stroke
				(width 0.508)
				(type default)
			)
			(layer "F.SilkS")
		)
		(fp_rect
			(start -0.9652 1.778)
			(end 0.9652 -1.778)
			(stroke
				(width 0)
				(type default)
			)
			(fill no)
			(layer "F.CrtYd")
		)
		(fp_poly
			(pts
				(xy -0.9652 -1.778) (xy 0.9652 -1.778) (xy 0.9652 1.778) (xy -0.9652 1.778)
			)
			(stroke
				(width 0)
				(type default)
			)
			(fill no)
			(layer "F.Fab")
		)
		(pad "1" smd rect
			(at 0 -0.9652)
			(size 1.397 1.143)
			(layers "F.Cu" "F.Mask" "F.Paste")
			(net "COMP_A_PGOOD")
		)
		(pad "2" smd rect
			(at 0 0.9652)
			(size 1.397 1.143)
			(layers "F.Cu" "F.Mask" "F.Paste")
			(net "GND")
		)
	)
	(footprint ""
		(layer "F.Cu")
		(at 365.0488 -143.4084 180)
		(property "Reference" "R1071"
			(at 0 0 180)
			(layer "F.SilkS")
			(hide yes)
			(effects
				(font
					(size 1.27 1.27)
				)
			)
		)
		(property "Value" "100R2D-GP"
			(at 0.064008 -3.993896 180)
			(unlocked yes)
			(layer "F.Fab")
			(hide yes)
			(effects
				(font
					(size 1.016 1.016)
					(thickness 0.1524)
				)
			)
		)
		(property "Device Type" "R402H14"
			(at 0.064008 -5.517896 180)
			(unlocked yes)
			(layer "F.Fab")
			(hide yes)
			(effects
				(font
					(size 1.016 1.016)
					(thickness 0.1524)
				)
			)
		)
		(duplicate_pad_numbers_are_jumpers no)
		(fp_line
			(start 0.508 -0.9398)
			(end -0.508 -0.9398)
			(stroke
				(width 0.1524)
				(type default)
			)
			(layer "F.SilkS")
		)
		(fp_line
			(start -0.508 -0.9398)
			(end -0.508 0.9398)
			(stroke
				(width 0.1524)
				(type default)
			)
			(layer "F.SilkS")
		)
		(fp_rect
			(start -0.508 0.9398)
			(end 0.508 -0.9398)
			(stroke
				(width 0)
				(type default)
			)
			(fill no)
			(layer "F.CrtYd")
		)
		(fp_rect
			(start -0.508 0.9398)
			(end 0.508 -0.9398)
			(stroke
				(width 0)
				(type default)
			)
			(fill no)
			(layer "F.Fab")
		)
		(pad "1" smd custom
			(at 0 -0.4445 180)
			(size 0.1397 0.1397)
			(layers "F.Cu" "F.Mask" "F.Paste")
			(net "MB1_TEMP")
			(options
				(clearance outline)
				(anchor circle)
			)
			(primitives
				(gr_poly
					(pts
						(arc
							(start -0.1778 -0.2794)
							(mid -0.249642 -0.249642)
							(end -0.2794 -0.1778)
						)
						(arc
							(start -0.2794 0.1778)
							(mid -0.249642 0.249642)
							(end -0.1778 0.2794)
						)
						(arc
							(start 0.1778 0.2794)
							(mid 0.249642 0.249642)
							(end 0.2794 0.1778)
						)
						(arc
							(start 0.2794 -0.1778)
							(mid 0.249642 -0.249642)
							(end 0.1778 -0.2794)
						)
					)
					(width 0)
					(fill yes)
				)
			)
		)
		(pad "2" smd custom
			(at 0 0.4445 180)
			(size 0.1397 0.1397)
			(layers "F.Cu" "F.Mask" "F.Paste")
			(net "MB1_TEMP_B")
			(options
				(clearance outline)
				(anchor circle)
			)
			(primitives
				(gr_poly
					(pts
						(arc
							(start -0.1778 -0.2794)
							(mid -0.249642 -0.249642)
							(end -0.2794 -0.1778)
						)
						(arc
							(start -0.2794 0.1778)
							(mid -0.249642 0.249642)
							(end -0.1778 0.2794)
						)
						(arc
							(start 0.1778 0.2794)
							(mid 0.249642 0.249642)
							(end 0.2794 0.1778)
						)
						(arc
							(start 0.2794 -0.1778)
							(mid 0.249642 -0.249642)
							(end 0.1778 -0.2794)
						)
					)
					(width 0)
					(fill yes)
				)
			)
		)
	)
	(footprint ""
		(layer "F.Cu")
		(at 341.376762 -33.995868 90)
		(property "Reference" "R379"
			(at 0 0 90)
			(layer "F.SilkS")
			(hide yes)
			(effects
				(font
					(size 1.27 1.27)
				)
			)
		)
		(property "Value" "100KR2F-L1-GP"
			(at 0.064008 -3.993896 90)
			(unlocked yes)
			(layer "F.Fab")
			(hide yes)
			(effects
				(font
					(size 1.016 1.016)
					(thickness 0.1524)
				)
			)
		)
		(property "Device Type" "R402H16"
			(at 0.064008 -5.517896 90)
			(unlocked yes)
			(layer "F.Fab")
			(hide yes)
			(effects
				(font
					(size 1.016 1.016)
					(thickness 0.1524)
				)
			)
		)
		(duplicate_pad_numbers_are_jumpers no)
		(fp_line
			(start 0.508 -0.9398)
			(end -0.508 -0.9398)
			(stroke
				(width 0.1524)
				(type default)
			)
			(layer "F.SilkS")
		)
		(fp_line
			(start -0.508 -0.9398)
			(end -0.508 0.9398)
			(stroke
				(width 0.1524)
				(type default)
			)
			(layer "F.SilkS")
		)
		(fp_rect
			(start -0.508 0.9398)
			(end 0.508 -0.9398)
			(stroke
				(width 0)
				(type default)
			)
			(fill no)
			(layer "F.CrtYd")
		)
		(fp_rect
			(start -0.508 0.9398)
			(end 0.508 -0.9398)
			(stroke
				(width 0)
				(type default)
			)
			(fill no)
			(layer "F.Fab")
		)
		(pad "1" smd custom
			(at 0 -0.4445 90)
			(size 0.1397 0.1397)
			(layers "F.Cu" "F.Mask" "F.Paste")
			(net "P3V3_STBY_B")
			(options
				(clearance outline)
				(anchor circle)
			)
			(primitives
				(gr_poly
					(pts
						(arc
							(start -0.1778 -0.2794)
							(mid -0.249642 -0.249642)
							(end -0.2794 -0.1778)
						)
						(arc
							(start -0.2794 0.1778)
							(mid -0.249642 0.249642)
							(end -0.1778 0.2794)
						)
						(arc
							(start 0.1778 0.2794)
							(mid 0.249642 0.249642)
							(end 0.2794 0.1778)
						)
						(arc
							(start 0.2794 -0.1778)
							(mid 0.249642 -0.249642)
							(end 0.1778 -0.2794)
						)
					)
					(width 0)
					(fill yes)
				)
			)
		)
		(pad "2" smd custom
			(at 0 0.4445 90)
			(size 0.1397 0.1397)
			(layers "F.Cu" "F.Mask" "F.Paste")
			(net "IOM_B_INS_N")
			(options
				(clearance outline)
				(anchor circle)
			)
			(primitives
				(gr_poly
					(pts
						(arc
							(start -0.1778 -0.2794)
							(mid -0.249642 -0.249642)
							(end -0.2794 -0.1778)
						)
						(arc
							(start -0.2794 0.1778)
							(mid -0.249642 0.249642)
							(end -0.1778 0.2794)
						)
						(arc
							(start 0.1778 0.2794)
							(mid 0.249642 0.249642)
							(end 0.2794 0.1778)
						)
						(arc
							(start 0.2794 -0.1778)
							(mid 0.249642 -0.249642)
							(end 0.1778 -0.2794)
						)
					)
					(width 0)
					(fill yes)
				)
			)
		)
	)
	(footprint ""
		(layer "F.Cu")
		(at 95.563436 -159.219392 90)
		(property "Reference" "C220"
			(at 0 0 90)
			(layer "F.SilkS")
			(hide yes)
			(effects
				(font
					(size 1.27 1.27)
				)
			)
		)
		(property "Value" "SCD01U16V1KX-GP"
			(at -2.8321 -1.7399 90)
			(unlocked yes)
			(layer "F.Fab")
			(hide yes)
			(effects
				(font
					(size 1.016 1.016)
					(thickness 0.1524)
				)
			)
		)
		(property "Device Type" "C0201H13"
			(at -2.8321 -3.2639 90)
			(unlocked yes)
			(layer "F.Fab")
			(hide yes)
			(effects
				(font
					(size 1.016 1.016)
					(thickness 0.1524)
				)
			)
		)
		(duplicate_pad_numbers_are_jumpers no)
		(fp_rect
			(start -0.2794 0.6477)
			(end 0.2794 -0.6477)
			(stroke
				(width 0)
				(type default)
			)
			(fill no)
			(layer "F.CrtYd")
		)
		(fp_rect
			(start -0.2794 0.6477)
			(end 0.2794 -0.6477)
			(stroke
				(width 0)
				(type default)
			)
			(fill no)
			(layer "F.Fab")
		)
		(pad "1" smd custom
			(at 0 -0.2794 90)
			(size 0.0762 0.0762)
			(layers "F.Cu" "F.Mask" "F.Paste")
			(net "SAS_HDD_RX_N14")
			(options
				(clearance outline)
				(anchor circle)
			)
			(primitives
				(gr_poly
					(pts
						(arc
							(start 0.1524 -0.127)
							(mid 0.137521 -0.162921)
							(end 0.1016 -0.1778)
						)
						(arc
							(start -0.1016 -0.1778)
							(mid -0.137521 -0.162921)
							(end -0.1524 -0.127)
						)
						(arc
							(start -0.1524 0.127)
							(mid -0.137521 0.162921)
							(end -0.1016 0.1778)
						)
						(arc
							(start 0.1016 0.1778)
							(mid 0.137521 0.162921)
							(end 0.1524 0.127)
						)
					)
					(width 0)
					(fill yes)
				)
			)
		)
		(pad "2" smd custom
			(at 0 0.2794 90)
			(size 0.0762 0.0762)
			(layers "F.Cu" "F.Mask" "F.Paste")
			(net "PHY_SCC_A_TO_DRV_A_14_DN")
			(options
				(clearance outline)
				(anchor circle)
			)
			(primitives
				(gr_poly
					(pts
						(arc
							(start 0.1524 -0.127)
							(mid 0.137521 -0.162921)
							(end 0.1016 -0.1778)
						)
						(arc
							(start -0.1016 -0.1778)
							(mid -0.137521 -0.162921)
							(end -0.1524 -0.127)
						)
						(arc
							(start -0.1524 0.127)
							(mid -0.137521 0.162921)
							(end -0.1016 0.1778)
						)
						(arc
							(start 0.1016 0.1778)
							(mid 0.137521 0.162921)
							(end 0.1524 0.127)
						)
					)
					(width 0)
					(fill yes)
				)
			)
		)
	)
	(footprint ""
		(layer "F.Cu")
		(at 175.550068 -209.399886)
		(property "Reference" "FLED6"
			(at 0 0 0)
			(layer "F.SilkS")
			(hide yes)
			(effects
				(font
					(size 1.27 1.27)
				)
			)
		)
		(property "Value" "LED-BY-19-GP"
			(at -2.132076 1.414018 0)
			(unlocked yes)
			(layer "F.Fab")
			(hide yes)
			(effects
				(font
					(size 1.016 1.016)
					(thickness 0.1524)
				)
			)
		)
		(property "Device Type" "LED-1615-4PH26"
			(at -2.132076 -0.109982 0)
			(unlocked yes)
			(layer "F.Fab")
			(hide yes)
			(effects
				(font
					(size 1.016 1.016)
					(thickness 0.1524)
				)
			)
		)
		(duplicate_pad_numbers_are_jumpers no)
		(fp_line
			(start -1.2954 0.254)
			(end -1.2954 1.6002)
			(stroke
				(width 0.508)
				(type default)
			)
			(layer "F.SilkS")
		)
		(fp_line
			(start -1.2954 1.6002)
			(end 1.2954 1.6002)
			(stroke
				(width 0.508)
				(type default)
			)
			(layer "F.SilkS")
		)
		(fp_line
			(start -1.1176 -1.4224)
			(end 1.1176 -1.4224)
			(stroke
				(width 0.1524)
				(type default)
			)
			(layer "F.SilkS")
		)
		(fp_line
			(start -1.1176 1.4224)
			(end -1.1176 -1.4224)
			(stroke
				(width 0.1524)
				(type default)
			)
			(layer "F.SilkS")
		)
		(fp_line
			(start 1.1176 -1.4224)
			(end 1.1176 1.4224)
			(stroke
				(width 0.1524)
				(type default)
			)
			(layer "F.SilkS")
		)
		(fp_line
			(start 1.1176 1.4224)
			(end -1.1176 1.4224)
			(stroke
				(width 0.1524)
				(type default)
			)
			(layer "F.SilkS")
		)
		(fp_line
			(start 1.2954 1.6002)
			(end 1.2954 0.254)
			(stroke
				(width 0.508)
				(type default)
			)
			(layer "F.SilkS")
		)
		(fp_rect
			(start -0.7493 0.8001)
			(end 0.7493 -0.8001)
			(stroke
				(width 0)
				(type default)
			)
			(fill no)
			(layer "F.CrtYd")
		)
		(fp_poly
			(pts
				(xy -1.3716 1.6764) (xy -1.3716 -1.6764) (xy 1.3716 -1.6764) (xy 1.3716 0.0635) (xy 0.7493 0.0635)
				(xy 0.7493 -0.8001) (xy -0.7493 -0.8001) (xy -0.7493 0.8001) (xy 0.7493 0.8001) (xy 0.7493 0.0762)
				(xy 1.3716 0.0762) (xy 1.3716 1.6764)
			)
			(stroke
				(width 0)
				(type default)
			)
			(fill no)
			(layer "F.CrtYd")
		)
		(fp_rect
			(start -1.3716 1.6764)
			(end 1.3716 -1.6764)
			(stroke
				(width 0)
				(type default)
			)
			(fill no)
			(layer "F.Fab")
		)
		(pad "1" smd rect
			(at 0.50038 -0.73025)
			(size 0.7112 0.8636)
			(layers "F.Cu" "F.Mask" "F.Paste")
			(net "DRV_ACT_5")
		)
		(pad "2" smd rect
			(at -0.50038 -0.73025)
			(size 0.7112 0.8636)
			(layers "F.Cu" "F.Mask" "F.Paste")
			(net "FLT_HDD5")
		)
		(pad "3" smd rect
			(at 0.50038 0.73025)
			(size 0.7112 0.8636)
			(layers "F.Cu" "F.Mask" "F.Paste")
			(net "DRV_ACT_5_N")
		)
		(pad "4" smd rect
			(at -0.50038 0.73025)
			(size 0.7112 0.8636)
			(layers "F.Cu" "F.Mask" "F.Paste")
			(net "FLT_HDD5_N")
		)
	)
)
